Altium Designer Pick and Place Locations
\\Mac\Home\Documents\GitHub\Time-Appliance-Project\Time-Card\GNSS\UBlox\NEO-M9N\Altium\ECAD\outputs\fab_844-XXXXX-XX\xydata\844-XXXXX-XX-RevX1.txt

========================================================================================================================
File Design Information:

Date:       06/01/23
Time:       20:08
Revision:   Not in VersionControl
Variant:    845-XXXXX_PCBA_projectname
Units used: mm

Designator Comment                   Layer    Footprint           Center-X(mm) Center-Y(mm) Rotation Description                                                                                  
R7         "0 ohm 0402"              TopLayer r0402               22.6000      7.2000       180      "RES SMD 0 OHM JUMPER 1/16W 0402"                                                            
Q1         DMG2302UKQ-7              TopLayer SOT23               12.1000      13.0000      90       "N-Channel 20 V 2.8A (Ta) 660mW (Ta) Surface Mount SOT-23-3"                                 
C5         "10nF 50V 0402"           TopLayer c0402               13.3000      17.4384      180      "CAP CER 10000PF 50V X7R 0402"                                                               
U1         NEO-M9N-00B               TopLayer IC_NEO-M9N          30.7000      15.5000      90       "GNSS module, Flash, TCXO, SAW, LNA, LCC, 12x16 mm Professional Grade"                       
TP11       1MM                       TopLayer TP1MM               61.0611      21.6000      90       "Test Point 1MM diameter"                                                                    
TP10       1MM                       TopLayer TP1MM               58.5060      21.6000      90       "Test Point 1MM diameter"                                                                    
TP9        1MM                       TopLayer TP1MM               32.2000      7.2000       0        "Test Point 1MM diameter"                                                                    
TP8        1MM                       TopLayer TP1MM               30.5000      7.2000       0        "Test Point 1MM diameter"                                                                    
TP7        1MM                       TopLayer TP1MM               38.2000      23.8000      0        "Test Point 1MM diameter"                                                                    
TP6        1MM                       TopLayer TP1MM               24.8000      7.2000       0        "Test Point 1MM diameter"                                                                    
TP5        1MM                       TopLayer TP1MM               34.3995      23.7147      0        "Test Point 1MM diameter"                                                                    
TP4        1MM                       TopLayer TP1MM               31.1001      25.3000      0        "Test Point 1MM diameter"                                                                    
TP3        1MM                       TopLayer TP1MM               32.1999      23.7147      0        "Test Point 1MM diameter"                                                                    
TP2        1MM                       TopLayer TP1MM               33.3000      25.3000      0        "Test Point 1MM diameter"                                                                    
TP1        1MM                       TopLayer TP1MM               36.6000      23.8000      0        "Test Point 1MM diameter"                                                                    
R8         "0 ohm 0402"              TopLayer r0402               61.0611      19.5000      270      "RES SMD 0 OHM JUMPER 1/16W 0402"                                                            
R5         "0 ohm 0402"              TopLayer r0402               58.5060      19.5000      270      "RES SMD 0 OHM JUMPER 1/16W 0402"                                                            
R4         "10 OHM 1/4W 0603"        TopLayer r0603               11.0000      16.6884      90       "Res Surge Chip Thick Film 0603 10 Ohm 1% 1/4W ±200ppm/°C Molded Paper T/R"                  
R3         "10K 1/8W 0402"           TopLayer r0402               52.8000      10.9000      90       "Res Thick Film 0402 10K Ohm 1% 0.125W(1/8W) ±100ppm/°C Pad SMD T/R"                         
R2         "10K 1/8W 0402"           TopLayer r0402               45.9000      10.9000      90       "Res Thick Film 0402 10K Ohm 1% 0.125W(1/8W) ±100ppm/°C Pad SMD T/R"                         
R1         "0 ohm 0402"              TopLayer r0402               29.3000      24.3000      90       "RES SMD 0 OHM JUMPER 1/16W 0402"                                                            
LED2       Green                     TopLayer led0603             51.0492      10.4746      90       "LED High-Power Uni-Color Green 574nm 2-Pin Chip LED T/R"                                    
LED1       Green                     TopLayer led0603             44.1492      10.4746      90       "LED High-Power Uni-Color Green 574nm 2-Pin Chip LED T/R"                                    
L1         "27nH 300mA 460mohm 0402" TopLayer L0402               10.7877      19.4000      90       "Inductor RF Chip Multi-Layer 27nH 5% 100MHz 8Q-Factor Air 300mA 460mOhm DCR 0402 Paper T/R" 
J2         SMB_131-3711-301          TopLayer CONN_131-3711-301   5.6631       19.7389      270      "Rf Coaxial Board Mount Connector"                                                           
J1         "NRPN042MAMS-RC 2MM"      TopLayer CONN_NRPN042MAMS-RC 61.0700      11.2800      180      "Dual Row 8 Position 2 mm Pitch Surface Mount Header"                                        
C4         "47pF 50V 0402"           TopLayer c0402               24.8009      24.4000      270      "0402 47 pF 50 V ±5 % Tolerance NP0 SMT Multilayer Ceramic Capacitor"                        
C3         "10nF 50V 0402"           TopLayer c0402               38.2990      6.7000       90       "CAP CER 10000PF 50V X7R 0402"                                                               
C2         "100nF 10V 0402"          TopLayer c0402               36.7557      6.7000       90       "CL05 Series 0.1 uF 10 V ±10 % Tolerance X7R SMT Multilayer Ceramic Capacitor"               
C1         "1uF 6V3 0402"            TopLayer c0402               35.2000      6.7000       90       "0402 1 uF 6.3 V ±10% Tolerance X7R Multilayer Ceramic Capacitor"                            
